FILE_TYPE = MACRO_DRAWING;
SET COLOR_WIRE YELLOW;
SET COLOR_PROP ORANGE;
SET COLOR_DOT WHITE;
SET COLOR_ARC YELLOW;
SET COLOR_BODY GREEN;
SET COLOR_NOTE PURPLE;
SET PROP_DISPLAY VALUE;
SET PAGE_NUMBER P172;
FORCEADD QUANTA_TITLE_BLOCK_C..1
(0 0);
FORCEPROP 1 LAST CUSTOM_TXT_CDS <NAME_2>
J 0
(-3175 50);
FORCEPROP 1 LAST CUSTOM_TXT_CDS <NAME_1>
J 0
(-3175 175);
FORCEPROP 1 LAST CUSTOM_TXT_CDS <Q_NUMBER>
J 0
(-1403 103);
DISPLAY 1.212766 (-1403 103);
FORCEPROP 1 LAST CUSTOM_TXT_CDS <Q_PROJ>
J 0
(-2382 102);
DISPLAY 1.212766 (-2382 102);
FORCEPROP 1 LAST CUSTOM_TXT_CDS <Q_REV>
J 0
(-184 103);
DISPLAY 1.212766 (-184 103);
FORCEPROP 1 LAST CUSTOM_TXT_CDS <CON_LAST_MODIFIED>
J 0
(-1885 15);
DISPLAY 0.978723 (-1885 15);
FORCEPROP 1 LAST CUSTOM_TXT_CDS <CON_PAGE_NUM> OF <CON_TOTAL_PAGES>
J 0
(-446 18);
DISPLAY 0.978723 (-446 18);
FORCEPROP 1 LAST Q_TITLE Blank
J 0
(-9366 26);
DISPLAY 2.446809 (-9366 26);
PAINT GREEN (-9366 26);
FORCEPROP 1 LAST Q_DEPT BU9
J 1
(-3763 49);
DISPLAY 1.957447 (-3763 49);
PAINT GREEN (-3763 49);
FORCEPROP 0 LAST CDS_CON_LAST_MODIFIED Fri Nov 05 18:01:49 2021
J 0
(-1885 15);
DISPLAY INVISIBLE (-1885 15);
FORCEPROP 2 LAST PAGE_BORDER TRUE
J 0
(-7890 5250);
DISPLAY 0.638298 (-7890 5250);
PAINT PINK (-7890 5250);
DISPLAY INVISIBLE (-7890 5250);
FORCEPROP 2 LAST CDS_LIB pure_quanta
J 0
(0 0);
DISPLAY INVISIBLE (0 0);
FORCEPROP 1 LAST CDS_LMAN_SYM_OUTLINE -9475,6775,100,-125
J 0
(0 0);
DISPLAY 0.468085 (0 0);
PAINT GREEN (0 0);
DISPLAY INVISIBLE (0 0);
FORCEPROP 1 LAST COMMENT_BODY TRUE
J 0
(12 -13);
DISPLAY 0.978723 (12 -13);
PAINT GREEN (12 -13);
DISPLAY INVISIBLE (12 -13);
FORCEPROP 2 LAST CUSTOM_TXT_CDS <XR_PAGE_TITLE>
J 0
(-7890 5250);
DISPLAY 0.638298 (-7890 5250);
PAINT PINK (-7890 5250);
DISPLAY INVISIBLE (-7890 5250);
FORCEPROP 2 LAST CDS_XR_PAGE_TITLE CR-173 : @T6G_MB_LIB.T6G(SCH_1):PAGE173
J 0
(-7890 5250);
DISPLAY 0.638298 (-7890 5250);
PAINT PINK (-7890 5250);
DISPLAY INVISIBLE (-7890 5250);
QUIT
